# BASEBOARD_FAB2 (Tioga Pass) — schematic netlist excerpt (pin names and nets, part order shuffled) for the footprints in the layout excerpt that follows; sources: Cadence DE-HDL packaged netlist, KiCad conversion of Wiwynn_Tioga_Pass_MB.brd

J6T1  SCONN288_H44441003  SCONN  pkg PIP  page 44
  \12v\(1)  = P12V_NVDIMM_ABC
  VSS(93)  = GND
  DQ(4)  = M_A_DQ<4>
  VSS(92)  = GND
  DQ(0)  = M_A_DQ<0>
  VSS(91)  = GND
  DQS9P  = M_A_DQS_DP<9>
  DQS9N  = M_A_DQS_DN<9>
  VSS(90)  = GND
  DQ(6)  = M_A_DQ<6>
  VSS(89)  = GND
  DQ(2)  = M_A_DQ<2>
  VSS(88)  = GND
  DQ(12)  = M_A_DQ<12>
  VSS(87)  = GND
  DQ(8)  = M_A_DQ<8>
  VSS(86)  = GND
  DQS10P  = M_A_DQS_DP<10>
  DQS10N  = M_A_DQS_DN<10>
  VSS(85)  = GND
  DQ(14)  = M_A_DQ<14>
  VSS(84)  = GND
  DQ(10)  = M_A_DQ<10>
  VSS(83)  = GND
  DQ(20)  = M_A_DQ<20>
  VSS(82)  = GND
  DQ(16)  = M_A_DQ<16>
  VSS(81)  = GND
  DQS11P  = M_A_DQS_DP<11>
  DQS11N  = M_A_DQS_DN<11>
  VSS(80)  = GND
  DQ(22)  = M_A_DQ<22>
  VSS(79)  = GND
  DQ(18)  = M_A_DQ<18>
  VSS(78)  = GND
  DQ(28)  = M_A_DQ<28>
  VSS(77)  = GND
  DQ(24)  = M_A_DQ<24>
  VSS(76)  = GND
  DQS12P  = M_A_DQS_DP<12>
  DQS12N  = M_A_DQS_DN<12>
  VSS(75)  = GND
  DQ(30)  = M_A_DQ<30>
  VSS(74)  = GND
  DQ(26)  = M_A_DQ<26>
  VSS(73)  = GND
  CB(4)  = M_A_ECC<4>
  VSS(72)  = GND
  CB(0)  = M_A_ECC<0>
  VSS(71)  = GND
  DQS17P  = M_A_DQS_DP<17>
  DQS17N  = M_A_DQS_DN<17>
  VSS(70)  = GND
  CB(6)  = M_A_ECC<6>
  VSS(69)  = GND
  CB(2)  = M_A_ECC<2>
  VSS(68)  = GND
  RESET_N  = M_ABC_RST_N
  VDD(25)  = PVDDQ_ABC
  CKE(0)  = M_A_CKE<2>
  VDD(24)  = PVDDQ_ABC
  ACT_N  = M_A_ACT_N
  BG(0)  = M_A_BG<0>
  VDD(23)  = PVDDQ_ABC
  A12  = M_A_MA<12>
  A9  = M_A_MA<9>
  VDD(22)  = PVDDQ_ABC
  A8  = M_A_MA<8>
  A6  = M_A_MA<6>
  VDD(21)  = PVDDQ_ABC
  A3  = M_A_MA<3>
  A1  = M_A_MA<1>
  VDD(20)  = PVDDQ_ABC
  CK0P  = M_A_CLK_DP<2>
  CK0N  = M_A_CLK_DN<2>
  VDD(19)  = PVDDQ_ABC
  VTT(1)  = PVTT_ABC
  EVENT_N  = FM_DIMM_EVENT_COD_N
  A0  = M_A_MA<0>
  VDD(18)  = PVDDQ_ABC
  BA(0)  = M_A_BA<0>
  A16_RAS_N  = M_A_MA<16>
  VDD(17)  = PVDDQ_ABC
  S0_N  = M_A_CS_N<4>
  VDD(16)  = PVDDQ_ABC
  A15_CAS_N  = M_A_MA<15>
  ODT(0)  = M_A_ODT<2>
  VDD(15)  = PVDDQ_ABC
  S1_N  = M_A_CS_N<5>
  VDD(14)  = PVDDQ_ABC
  ODT(1)  = M_A_ODT<3>
  VDD(13)  = PVDDQ_ABC
  S2_N_C(0)  = M_A_CS_N<6>
  VSS(67)  = GND
  DQ(36)  = M_A_DQ<36>
  VSS(66)  = GND
  DQ(32)  = M_A_DQ<32>
  VSS(65)  = GND
  DQS13P  = M_A_DQS_DP<13>
  DQS13N  = M_A_DQS_DN<13>
  VSS(64)  = GND
  DQ(38)  = M_A_DQ<38>
  VSS(63)  = GND
  DQ(34)  = M_A_DQ<34>
  VSS(62)  = GND
  DQ(44)  = M_A_DQ<44>
  VSS(61)  = GND
  DQ(40)  = M_A_DQ<40>
  VSS(60)  = GND
  DQS14P  = M_A_DQS_DP<14>
  DQS14N  = M_A_DQS_DN<14>
  VSS(59)  = GND
  DQ(46)  = M_A_DQ<46>
  VSS(58)  = GND
  DQ(42)  = M_A_DQ<42>
  VSS(57)  = GND
  DQ(52)  = M_A_DQ<52>
  VSS(56)  = GND
  DQ(48)  = M_A_DQ<48>
  VSS(55)  = GND
  DQS15P  = M_A_DQS_DP<15>
  DQS15N  = M_A_DQS_DN<15>
  VSS(54)  = GND
  DQ(54)  = M_A_DQ<54>
  VSS(53)  = GND
  DQ(50)  = M_A_DQ<50>
  VSS(52)  = GND
  DQ(60)  = M_A_DQ<60>
  VSS(51)  = GND
  DQ(56)  = M_A_DQ<56>
  VSS(50)  = GND
  DQS16P  = M_A_DQS_DP<16>
  DQS16N  = M_A_DQS_DN<16>
  VSS(49)  = GND
  DQ(62)  = M_A_DQ<62>
  VSS(48)  = GND
  DQ(58)  = M_A_DQ<58>
  VSS(47)  = GND
  SA(0)  = PVPP_ABC
  SA(1)  = GND
  SCL  = SMB_DDR_ABC_VPP_SCL
  VPP(4)  = PVPP_ABC
  VPP(3)  = PVPP_ABC
  RFU(2)  = TP_CH_A_DIMM_A1_RFU_2
  \12v\(0)  = P12V_NVDIMM_ABC
  VREFCA  = M_A_VREF
  VSS(46)  = GND
  DQ(5)  = M_A_DQ<5>
  VSS(45)  = GND
  DQ(1)  = M_A_DQ<1>
  VSS(44)  = GND
  DQS0N  = M_A_DQS_DN<0>
  DQS0P  = M_A_DQS_DP<0>
  VSS(43)  = GND
  DQ(7)  = M_A_DQ<7>
  VSS(42)  = GND
  DQ(3)  = M_A_DQ<3>
  VSS(41)  = GND
  DQ(13)  = M_A_DQ<13>
  VSS(40)  = GND
  DQ(9)  = M_A_DQ<9>
  VSS(39)  = GND
  DQS1N  = M_A_DQS_DN<1>
  DQS1P  = M_A_DQS_DP<1>
  VSS(38)  = GND
  DQ(15)  = M_A_DQ<15>
  VSS(37)  = GND
  DQ(11)  = M_A_DQ<11>
  VSS(36)  = GND
  DQ(21)  = M_A_DQ<21>
  VSS(35)  = GND
  DQ(17)  = M_A_DQ<17>
  VSS(34)  = GND
  DQS2N  = M_A_DQS_DN<2>
  DQS2P  = M_A_DQS_DP<2>
  VSS(33)  = GND
  DQ(23)  = M_A_DQ<23>
  VSS(32)  = GND
  DQ(19)  = M_A_DQ<19>
  VSS(31)  = GND
  DQ(29)  = M_A_DQ<29>
  VSS(30)  = GND
  DQ(25)  = M_A_DQ<25>
  VSS(29)  = GND
  DQS3N  = M_A_DQS_DN<3>
  DQS3P  = M_A_DQS_DP<3>
  VSS(28)  = GND
  DQ(31)  = M_A_DQ<31>
  VSS(27)  = GND
  DQ(27)  = M_A_DQ<27>
  VSS(26)  = GND
  CB(5)  = M_A_ECC<5>
  VSS(25)  = GND
  CB(1)  = M_A_ECC<1>
  VSS(24)  = GND
  DQS8N  = M_A_DQS_DN<8>
  DQS8P  = M_A_DQS_DP<8>
  VSS(23)  = GND
  CB(7)  = M_A_ECC<7>
  VSS(22)  = GND
  CB(3)  = M_A_ECC<3>
  VSS(21)  = GND
  CKE(1)  = M_A_CKE<3>
  VDD(12)  = PVDDQ_ABC
  RFU(0)  = TP_CH_A_DIMM_A1_RFU_0
  VDD(11)  = PVDDQ_ABC
  BG(1)  = M_A_BG<1>
  ALERT_N  = M_A_ALERT_N
  VDD(10)  = PVDDQ_ABC
  A11  = M_A_MA<11>
  A7  = M_A_MA<7>
  VDD(9)  = PVDDQ_ABC
  A5  = M_A_MA<5>
  A4  = M_A_MA<4>
  VDD(8)  = PVDDQ_ABC
  A2  = M_A_MA<2>
  VDD(7)  = PVDDQ_ABC
  CK1P  = M_A_CLK_DP<3>
  CK1N  = M_A_CLK_DN<3>
  VDD(6)  = PVDDQ_ABC
  VTT(0)  = PVTT_ABC
  PAR  = M_A_PAR
  VDD(5)  = PVDDQ_ABC
  BA(1)  = M_A_BA<1>
  A10  = M_A_MA<10>
  VDD(4)  = PVDDQ_ABC
  RFU(1)  = TP_CH_A_DIMM_A1_RFU_1
  A14_WE_N  = M_A_MA<14>
  VDD(3)  = PVDDQ_ABC
  SAVE_N_NC  = FM_ADR_COMPLETE_ABC_N
  VDD(2)  = PVDDQ_ABC
  A13  = M_A_MA<13>
  VDD(1)  = PVDDQ_ABC
  A17  = M_A_MA<17>
  C(2)  = M_A_C<2>
  VDD(0)  = PVDDQ_ABC
  S3_N_C(1)  = M_A_CS_N<7>
  SA(2)  = GND
  VSS(20)  = GND
  DQ(37)  = M_A_DQ<37>
  VSS(19)  = GND
  DQ(33)  = M_A_DQ<33>
  VSS(18)  = GND
  DQS4N  = M_A_DQS_DN<4>
  DQS4P  = M_A_DQS_DP<4>
  VSS(17)  = GND
  DQ(39)  = M_A_DQ<39>
  VSS(16)  = GND
  DQ(35)  = M_A_DQ<35>
  VSS(15)  = GND
  DQ(45)  = M_A_DQ<45>
  VSS(14)  = GND
  DQ(41)  = M_A_DQ<41>
  VSS(13)  = GND
  DQS5N  = M_A_DQS_DN<5>
  DQS5P  = M_A_DQS_DP<5>
  VSS(12)  = GND
  DQ(47)  = M_A_DQ<47>
  VSS(11)  = GND
  DQ(43)  = M_A_DQ<43>
  VSS(10)  = GND
  DQ(53)  = M_A_DQ<53>
  VSS(9)  = GND
  DQ(49)  = M_A_DQ<49>
  VSS(8)  = GND
  DQS6N  = M_A_DQS_DN<6>
  DQS6P  = M_A_DQS_DP<6>
  VSS(7)  = GND
  DQ(55)  = M_A_DQ<55>
  VSS(6)  = GND
  DQ(51)  = M_A_DQ<51>
  VSS(5)  = GND
  DQ(61)  = M_A_DQ<61>
  VSS(4)  = GND
  DQ(57)  = M_A_DQ<57>
  VSS(3)  = GND
  DQS7N  = M_A_DQS_DN<7>
  DQS7P  = M_A_DQS_DP<7>
  VSS(2)  = GND
  DQ(63)  = M_A_DQ<63>
  VSS(1)  = GND
  DQ(59)  = M_A_DQ<59>
  VSS(0)  = GND
  VDDSPD  = PVPP_ABC
  SDA  = SMB_DDR_ABC_VPP_SDA
  VPP(1)  = PVPP_ABC
  VPP(0)  = PVPP_ABC
  VPP(2)  = PVPP_ABC

(kicad_pcb
	(version 20260206)
	(generator "pcbnew")
	(generator_version "10.0")
	(general
		(thickness 1.6)
		(legacy_teardrops no)
	)
	(paper "A4")
	(title_block
		(title "Wiwynn_Tioga_Pass_MB.brd")
		(comment 1 "Tioga Pass / footprint 3283 of 4770 (J6T1), pads 1-50 of 291")
	)
	(layers
		(0 "F.Cu" signal "TOP")
		(4 "In1.Cu" signal "L2GND")
		(6 "In2.Cu" signal "L3")
		(8 "In3.Cu" signal "L4GND")
		(10 "In4.Cu" signal "L5")
		(12 "In5.Cu" signal "L6GND")
		(14 "In6.Cu" signal "L7VCC")
		(16 "In7.Cu" signal "L8VCC")
		(18 "In8.Cu" signal "L9GND")
		(20 "In9.Cu" signal "L10")
		(22 "In10.Cu" signal "L11GND")
		(24 "In11.Cu" signal "L12")
		(26 "In12.Cu" signal "L13GND")
		(2 "B.Cu" signal "BOTTOM")
		(9 "F.Adhes" user "F.Adhesive")
		(11 "B.Adhes" user "B.Adhesive")
		(13 "F.Paste" user "Package Geometry/Pastemask Top")
		(15 "B.Paste" user "Package Geometry/Pastemask Bottom")
		(5 "F.SilkS" user "Ref Des/Silkscreen Top")
		(7 "B.SilkS" user "Ref Des/Silkscreen Bottom")
		(1 "F.Mask" user "Board Geometry/Soldermask Top")
		(3 "B.Mask" user "Board Geometry/Soldermask Bottom")
		(17 "Dwgs.User" user "User.Drawings")
		(19 "Cmts.User" user "User.Comments")
		(21 "Eco1.User" user "User.Eco1")
		(23 "Eco2.User" user "User.Eco2")
		(25 "Edge.Cuts" user "Board Geometry/Outline")
		(27 "Margin" user)
		(31 "F.CrtYd" user "Package Geometry/Place Bound Top")
		(29 "B.CrtYd" user "Package Geometry/Place Bound Bottom")
		(35 "F.Fab" user "Ref Des/Assembly Top")
		(33 "B.Fab" user "Ref Des/Assembly Bottom")
	)
	(footprint ""
		(layer "B.Cu")
		(at 194.700398 -24.824182 90)
		(property "Reference" "J6T1"
			(at 2.200148 39.23411 0)
			(unlocked yes)
			(layer "B.SilkS")
			(effects
				(font
					(size 0.7874 0.5842)
					(thickness 0.1524)
				)
				(justify left mirror)
			)
		)
		(property "Value" ""
			(at 0 0 90)
			(layer "B.Fab")
			(effects
				(font
					(size 1.27 1.27)
				)
				(justify mirror)
			)
		)
		(duplicate_pad_numbers_are_jumpers no)
		(pad "" thru_hole circle
			(at -2.29997 -5.649976 270)
			(size 2.8194 2.8194)
			(drill 2.4384)
			(layers "*.Cu" "*.Mask")
			(remove_unused_layers no)
			(clearance 0.127)
			(thermal_gap 0.127)
		)
		(pad "" thru_hole oval
			(at -2.29997 68.90004 270)
			(size 2.8194 1.5748)
			(drill oval 2.4384 1.1938)
			(layers "*.Cu" "*.Mask")
			(remove_unused_layers no)
			(clearance 0.127)
			(thermal_gap 0.127)
		)
		(pad "" thru_hole circle
			(at -2.29997 132.299964 270)
			(size 2.8194 2.8194)
			(drill 2.4384)
			(layers "*.Cu" "*.Mask")
			(remove_unused_layers no)
			(clearance 0.127)
			(thermal_gap 0.127)
		)
		(pad "1" smd rect
			(at 0 0 270)
			(size 1.8034 0.508)
			(layers "B.Cu" "B.Mask" "B.Paste")
			(net "P12V_NVDIMM_ABC")
		)
		(pad "2" smd rect
			(at 0 0.849884 270)
			(size 1.8034 0.508)
			(layers "B.Cu" "B.Mask" "B.Paste")
			(net "GND")
		)
		(pad "3" smd rect
			(at 0 1.700022 270)
			(size 1.8034 0.508)
			(layers "B.Cu" "B.Mask" "B.Paste")
			(net "M_A_DQ<4>")
		)
		(pad "4" smd rect
			(at 0 2.549906 270)
			(size 1.8034 0.508)
			(layers "B.Cu" "B.Mask" "B.Paste")
			(net "GND")
		)
		(pad "5" smd rect
			(at 0 3.400044 270)
			(size 1.8034 0.508)
			(layers "B.Cu" "B.Mask" "B.Paste")
			(net "M_A_DQ<0>")
		)
		(pad "6" smd rect
			(at 0 4.249928 270)
			(size 1.8034 0.508)
			(layers "B.Cu" "B.Mask" "B.Paste")
			(net "GND")
		)
		(pad "7" smd rect
			(at 0 5.100066 270)
			(size 1.8034 0.508)
			(layers "B.Cu" "B.Mask" "B.Paste")
			(net "M_A_DQS_DP<9>")
		)
		(pad "8" smd rect
			(at 0 5.94995 270)
			(size 1.8034 0.508)
			(layers "B.Cu" "B.Mask" "B.Paste")
			(net "M_A_DQS_DN<9>")
		)
		(pad "9" smd rect
			(at 0 6.800088 270)
			(size 1.8034 0.508)
			(layers "B.Cu" "B.Mask" "B.Paste")
			(net "GND")
		)
		(pad "10" smd rect
			(at 0 7.649972 270)
			(size 1.8034 0.508)
			(layers "B.Cu" "B.Mask" "B.Paste")
			(net "M_A_DQ<6>")
		)
		(pad "11" smd rect
			(at 0 8.50011 270)
			(size 1.8034 0.508)
			(layers "B.Cu" "B.Mask" "B.Paste")
			(net "GND")
		)
		(pad "12" smd rect
			(at 0 9.349994 270)
			(size 1.8034 0.508)
			(layers "B.Cu" "B.Mask" "B.Paste")
			(net "M_A_DQ<2>")
		)
		(pad "13" smd rect
			(at 0 10.199878 270)
			(size 1.8034 0.508)
			(layers "B.Cu" "B.Mask" "B.Paste")
			(net "GND")
		)
		(pad "14" smd rect
			(at 0 11.050016 270)
			(size 1.8034 0.508)
			(layers "B.Cu" "B.Mask" "B.Paste")
			(net "M_A_DQ<12>")
		)
		(pad "15" smd rect
			(at 0 11.8999 270)
			(size 1.8034 0.508)
			(layers "B.Cu" "B.Mask" "B.Paste")
			(net "GND")
		)
		(pad "16" smd rect
			(at 0 12.750038 270)
			(size 1.8034 0.508)
			(layers "B.Cu" "B.Mask" "B.Paste")
			(net "M_A_DQ<8>")
		)
		(pad "17" smd rect
			(at 0 13.599922 270)
			(size 1.8034 0.508)
			(layers "B.Cu" "B.Mask" "B.Paste")
			(net "GND")
		)
		(pad "18" smd rect
			(at 0 14.45006 270)
			(size 1.8034 0.508)
			(layers "B.Cu" "B.Mask" "B.Paste")
			(net "M_A_DQS_DP<10>")
		)
		(pad "19" smd rect
			(at 0 15.299944 270)
			(size 1.8034 0.508)
			(layers "B.Cu" "B.Mask" "B.Paste")
			(net "M_A_DQS_DN<10>")
		)
		(pad "20" smd rect
			(at 0 16.150082 270)
			(size 1.8034 0.508)
			(layers "B.Cu" "B.Mask" "B.Paste")
			(net "GND")
		)
		(pad "21" smd rect
			(at 0 16.999966 270)
			(size 1.8034 0.508)
			(layers "B.Cu" "B.Mask" "B.Paste")
			(net "M_A_DQ<14>")
		)
		(pad "22" smd rect
			(at 0 17.850104 270)
			(size 1.8034 0.508)
			(layers "B.Cu" "B.Mask" "B.Paste")
			(net "GND")
		)
		(pad "23" smd rect
			(at 0 18.699988 270)
			(size 1.8034 0.508)
			(layers "B.Cu" "B.Mask" "B.Paste")
			(net "M_A_DQ<10>")
		)
		(pad "24" smd rect
			(at 0 19.550126 270)
			(size 1.8034 0.508)
			(layers "B.Cu" "B.Mask" "B.Paste")
			(net "GND")
		)
		(pad "25" smd rect
			(at 0 20.40001 270)
			(size 1.8034 0.508)
			(layers "B.Cu" "B.Mask" "B.Paste")
			(net "M_A_DQ<20>")
		)
		(pad "26" smd rect
			(at 0 21.249894 270)
			(size 1.8034 0.508)
			(layers "B.Cu" "B.Mask" "B.Paste")
			(net "GND")
		)
		(pad "27" smd rect
			(at 0 22.100032 270)
			(size 1.8034 0.508)
			(layers "B.Cu" "B.Mask" "B.Paste")
			(net "M_A_DQ<16>")
		)
		(pad "28" smd rect
			(at 0 22.949916 270)
			(size 1.8034 0.508)
			(layers "B.Cu" "B.Mask" "B.Paste")
			(net "GND")
		)
		(pad "29" smd rect
			(at 0 23.800054 270)
			(size 1.8034 0.508)
			(layers "B.Cu" "B.Mask" "B.Paste")
			(net "M_A_DQS_DP<11>")
		)
		(pad "30" smd rect
			(at 0 24.649938 270)
			(size 1.8034 0.508)
			(layers "B.Cu" "B.Mask" "B.Paste")
			(net "M_A_DQS_DN<11>")
		)
		(pad "31" smd rect
			(at 0 25.500076 270)
			(size 1.8034 0.508)
			(layers "B.Cu" "B.Mask" "B.Paste")
			(net "GND")
		)
		(pad "32" smd rect
			(at 0 26.34996 270)
			(size 1.8034 0.508)
			(layers "B.Cu" "B.Mask" "B.Paste")
			(net "M_A_DQ<22>")
		)
		(pad "33" smd rect
			(at 0 27.200098 270)
			(size 1.8034 0.508)
			(layers "B.Cu" "B.Mask" "B.Paste")
			(net "GND")
		)
		(pad "34" smd rect
			(at 0 28.049982 270)
			(size 1.8034 0.508)
			(layers "B.Cu" "B.Mask" "B.Paste")
			(net "M_A_DQ<18>")
		)
		(pad "35" smd rect
			(at 0 28.90012 270)
			(size 1.8034 0.508)
			(layers "B.Cu" "B.Mask" "B.Paste")
			(net "GND")
		)
		(pad "36" smd rect
			(at 0 29.750004 270)
			(size 1.8034 0.508)
			(layers "B.Cu" "B.Mask" "B.Paste")
			(net "M_A_DQ<28>")
		)
		(pad "37" smd rect
			(at 0 30.599888 270)
			(size 1.8034 0.508)
			(layers "B.Cu" "B.Mask" "B.Paste")
			(net "GND")
		)
		(pad "38" smd rect
			(at 0 31.450026 270)
			(size 1.8034 0.508)
			(layers "B.Cu" "B.Mask" "B.Paste")
			(net "M_A_DQ<24>")
		)
		(pad "39" smd rect
			(at 0 32.29991 270)
			(size 1.8034 0.508)
			(layers "B.Cu" "B.Mask" "B.Paste")
			(net "GND")
		)
		(pad "40" smd rect
			(at 0 33.150048 270)
			(size 1.8034 0.508)
			(layers "B.Cu" "B.Mask" "B.Paste")
			(net "M_A_DQS_DP<12>")
		)
		(pad "41" smd rect
			(at 0 33.999932 270)
			(size 1.8034 0.508)
			(layers "B.Cu" "B.Mask" "B.Paste")
			(net "M_A_DQS_DN<12>")
		)
		(pad "42" smd rect
			(at 0 34.85007 270)
			(size 1.8034 0.508)
			(layers "B.Cu" "B.Mask" "B.Paste")
			(net "GND")
		)
		(pad "43" smd rect
			(at 0 35.699954 270)
			(size 1.8034 0.508)
			(layers "B.Cu" "B.Mask" "B.Paste")
			(net "M_A_DQ<30>")
		)
		(pad "44" smd rect
			(at 0 36.550092 270)
			(size 1.8034 0.508)
			(layers "B.Cu" "B.Mask" "B.Paste")
			(net "GND")
		)
		(pad "45" smd rect
			(at 0 37.399976 270)
			(size 1.8034 0.508)
			(layers "B.Cu" "B.Mask" "B.Paste")
			(net "M_A_DQ<26>")
		)
		(pad "46" smd rect
			(at 0 38.250114 270)
			(size 1.8034 0.508)
			(layers "B.Cu" "B.Mask" "B.Paste")
			(net "GND")
		)
		(pad "47" smd rect
			(at 0 39.099998 270)
			(size 1.8034 0.508)
			(layers "B.Cu" "B.Mask" "B.Paste")
			(net "M_A_ECC<4>")
		)
	)
)
